# TIMECARD (Time Appliance Project (Time Card)) — schematic netlist excerpt (pin names and nets, part order shuffled) for the footprints in the layout excerpt that follows; sources: Cadence DE-HDL packaged netlist, KiCad conversion of R4006-B0001-02_R01.brd

C54  CAPACITOR  2200PF 50V 10%  pkg SMC_0402R_H022  page 28 : \1\ = UNNAMED_517_CAPACITOR_I17_1 ; \2\ = XP3R3V_AGND
C162  CAPACITOR  0.1UF 10V 10%  pkg SMC_0402R_H022  page 14 : \1\ = XP3R3V_FPGA ; \2\ = SG

(kicad_pcb
	(version 20260206)
	(generator "pcbnew")
	(generator_version "10.0")
	(general
		(thickness 1.6)
		(legacy_teardrops no)
	)
	(paper "A4")
	(title_block
		(title "timecard-production-celestica-r4006 — R4006-B0001-02_R01.brd")
		(comment 1 "Time Appliance Project (Time Card) / footprints 831-832 of 1113")
	)
	(layers
		(0 "F.Cu" signal "TOP")
		(4 "In1.Cu" signal "L02_GND1")
		(6 "In2.Cu" signal "L03_SIG1")
		(8 "In3.Cu" signal "L04_GND2")
		(10 "In4.Cu" signal "L05_VCC1")
		(12 "In5.Cu" signal "L06_VCC2")
		(14 "In6.Cu" signal "L07_GND3")
		(16 "In7.Cu" signal "L08_SIG2")
		(18 "In8.Cu" signal "L09_GND4")
		(2 "B.Cu" signal "BOTTOM")
		(9 "F.Adhes" user "F.Adhesive")
		(11 "B.Adhes" user "B.Adhesive")
		(13 "F.Paste" user "Package Geometry/Pastemask Top")
		(15 "B.Paste" user "Package Geometry/Pastemask Bottom")
		(5 "F.SilkS" user "Ref Des/Silkscreen Top")
		(7 "B.SilkS" user "Ref Des/Silkscreen Bottom")
		(1 "F.Mask" user "Board Geometry/Soldermask Top")
		(3 "B.Mask" user "Board Geometry/Soldermask Bottom")
		(17 "Dwgs.User" user "User.Drawings")
		(19 "Cmts.User" user "User.Comments")
		(21 "Eco1.User" user "User.Eco1")
		(23 "Eco2.User" user "User.Eco2")
		(25 "Edge.Cuts" user "Board Geometry/Outline")
		(27 "Margin" user)
		(31 "F.CrtYd" user "Package Geometry/Place Bound Top")
		(29 "B.CrtYd" user "Package Geometry/Place Bound Bottom")
		(35 "F.Fab" user "Ref Des/Assembly Top")
		(33 "B.Fab" user "Ref Des/Assembly Bottom")
	)
	(footprint ""
		(layer "B.Cu")
		(at 107.84713 -54.323234 -90)
		(property "Reference" "C162"
			(at -0.286766 -1.34112 270)
			(unlocked yes)
			(layer "B.SilkS")
			(effects
				(font
					(size 0.635 0.4064)
					(thickness 0.1524)
				)
				(justify mirror)
			)
		)
		(property "Value" "VAL*"
			(at 0 3.718306 270)
			(unlocked yes)
			(layer "B.Fab")
			(hide yes)
			(effects
				(font
					(size 0.7874 0.5842)
					(thickness 0.127)
				)
				(justify mirror)
			)
		)
		(property "Tolerance" "TOL*"
			(at 0 4.861306 270)
			(unlocked yes)
			(layer "Cmts.User")
			(hide yes)
			(effects
				(font
					(size 0.7874 0.5842)
					(thickness 0.127)
				)
				(justify mirror)
			)
		)
		(property "User Part Number" "PARTNUM*"
			(at 0 2.575306 270)
			(unlocked yes)
			(layer "Cmts.User")
			(hide yes)
			(effects
				(font
					(size 0.7874 0.5842)
					(thickness 0.127)
				)
				(justify mirror)
			)
		)
		(property "Device Type" "CAPACITOR-G105-0B104-CK,0.1UF,A"
			(at 0 1.432306 270)
			(unlocked yes)
			(layer "B.Fab")
			(hide yes)
			(effects
				(font
					(size 0.7874 0.5842)
					(thickness 0.127)
				)
				(justify mirror)
			)
		)
		(duplicate_pad_numbers_are_jumpers no)
		(fp_line
			(start -0.970026 0.4699)
			(end 0.970026 0.4699)
			(stroke
				(width 0.1)
				(type default)
			)
			(layer "B.SilkS")
		)
		(fp_line
			(start 0.970026 0.4699)
			(end 0.970026 -0.4699)
			(stroke
				(width 0.1)
				(type default)
			)
			(layer "B.SilkS")
		)
		(fp_line
			(start -0.970026 -0.4699)
			(end -0.970026 0.4699)
			(stroke
				(width 0.1)
				(type default)
			)
			(layer "B.SilkS")
		)
		(fp_line
			(start 0.970026 -0.4699)
			(end -0.970026 -0.4699)
			(stroke
				(width 0.1)
				(type default)
			)
			(layer "B.SilkS")
		)
		(fp_poly
			(pts
				(xy 0.970026 0.4699) (xy -0.970026 0.4699) (xy -0.970026 -0.4699) (xy 0.970026 -0.4699)
			)
			(stroke
				(width 0)
				(type default)
			)
			(fill no)
			(layer "B.CrtYd")
		)
		(fp_line
			(start -0.508 0.3048)
			(end 0.508 0.3048)
			(stroke
				(width 0.1)
				(type default)
			)
			(layer "B.Fab")
		)
		(fp_line
			(start 0.508 0.3048)
			(end 0.508 -0.3048)
			(stroke
				(width 0.1)
				(type default)
			)
			(layer "B.Fab")
		)
		(fp_line
			(start -0.508 -0.3048)
			(end -0.508 0.3048)
			(stroke
				(width 0.1)
				(type default)
			)
			(layer "B.Fab")
		)
		(fp_line
			(start 0.508 -0.3048)
			(end -0.508 -0.3048)
			(stroke
				(width 0.1)
				(type default)
			)
			(layer "B.Fab")
		)
		(pad "1" smd circle
			(at 0.500126 0 90)
			(size 0.635 0.635)
			(layers "B.Cu" "B.Mask" "B.Paste")
			(net "XP3R3V_FPGA")
		)
		(pad "2" smd circle
			(at -0.500126 0 90)
			(size 0.635 0.635)
			(layers "B.Cu" "B.Mask" "B.Paste")
			(net "SG")
		)
	)
	(footprint ""
		(layer "B.Cu")
		(at 89.9922 -100.1268)
		(property "Reference" "C54"
			(at 3.683 0.03937 0)
			(unlocked yes)
			(layer "B.SilkS")
			(effects
				(font
					(size 0.7874 0.5842)
					(thickness 0.1524)
				)
				(justify mirror)
			)
		)
		(property "Value" "VAL*"
			(at -0.0762 2.067306 0)
			(unlocked yes)
			(layer "B.Fab")
			(hide yes)
			(effects
				(font
					(size 0.7874 0.5842)
					(thickness 0.1524)
				)
				(justify mirror)
			)
		)
		(property "Tolerance" "TOL*"
			(at -0.0762 3.032506 0)
			(unlocked yes)
			(layer "Cmts.User")
			(hide yes)
			(effects
				(font
					(size 0.7874 0.5842)
					(thickness 0.1524)
				)
				(justify mirror)
			)
		)
		(property "User Part Number" "PARTNUM*"
			(at -0.1016 4.023106 0)
			(unlocked yes)
			(layer "Cmts.User")
			(hide yes)
			(effects
				(font
					(size 0.7874 0.5842)
					(thickness 0.1524)
				)
				(justify mirror)
			)
		)
		(property "Device Type" "CAPACITOR-G105-0B222-FK,2200PFA"
			(at -0.0508 1.127506 0)
			(unlocked yes)
			(layer "B.Fab")
			(hide yes)
			(effects
				(font
					(size 0.7874 0.5842)
					(thickness 0.1524)
				)
				(justify mirror)
			)
		)
		(duplicate_pad_numbers_are_jumpers no)
		(fp_line
			(start -1.143 -0.5588)
			(end 1.143 -0.5588)
			(stroke
				(width 0.1)
				(type default)
			)
			(layer "B.SilkS")
		)
		(fp_line
			(start -1.143 0.5588)
			(end -1.143 -0.5588)
			(stroke
				(width 0.1)
				(type default)
			)
			(layer "B.SilkS")
		)
		(fp_line
			(start 1.143 -0.5588)
			(end 1.143 0.5588)
			(stroke
				(width 0.1)
				(type default)
			)
			(layer "B.SilkS")
		)
		(fp_line
			(start 1.143 0.5588)
			(end -1.143 0.5588)
			(stroke
				(width 0.1)
				(type default)
			)
			(layer "B.SilkS")
		)
		(fp_rect
			(start -1.143 0.5588)
			(end 1.143 -0.5588)
			(stroke
				(width 0)
				(type default)
			)
			(fill no)
			(layer "B.CrtYd")
		)
		(fp_line
			(start -0.508 -0.3048)
			(end 0.508 -0.3048)
			(stroke
				(width 0.1)
				(type default)
			)
			(layer "B.Fab")
		)
		(fp_line
			(start -0.508 0.3048)
			(end -0.508 -0.3048)
			(stroke
				(width 0.1)
				(type default)
			)
			(layer "B.Fab")
		)
		(fp_line
			(start 0.508 -0.3048)
			(end 0.508 0.3048)
			(stroke
				(width 0.1)
				(type default)
			)
			(layer "B.Fab")
		)
		(fp_line
			(start 0.508 0.3048)
			(end -0.508 0.3048)
			(stroke
				(width 0.1)
				(type default)
			)
			(layer "B.Fab")
		)
		(pad "1" smd rect
			(at 0.5334 0 180)
			(size 0.7112 0.6096)
			(layers "B.Cu" "B.Mask" "B.Paste")
			(net "UNNAMED_517_CAPACITOR_I17_1")
		)
		(pad "2" smd rect
			(at -0.5334 0 180)
			(size 0.7112 0.6096)
			(layers "B.Cu" "B.Mask" "B.Paste")
			(net "XP3R3V_AGND")
		)
		(zone
			(layer "B.Cu")
			(hatch none 0.5)
			(connect_pads
				(clearance 0)
			)
			(min_thickness 0.25)
			(keepout
				(tracks allowed)
				(vias not_allowed)
				(pads allowed)
				(copperpour not_allowed)
				(footprints allowed)
			)
			(placement
				(enabled no)
				(sheetname "")
			)
			(fill
				(thermal_gap 0.5)
				(thermal_bridge_width 0.5)
				(island_removal_mode 0)
			)
			(polygon
				(pts
					(xy 89.916 -99.822) (xy 90.0684 -99.822) (xy 90.0684 -100.4316) (xy 89.916 -100.4316)
				)
			)
		)
	)
)
